# T6G (Grand Teton) — schematic netlist excerpt (pin names and nets, part order shuffled) for the footprints in the layout excerpt that follows; sources: Cadence DE-HDL packaged netlist, KiCad conversion of 04192023_DAF0TMB3IC0_F0TG_MB_C_brd_V02_OCP.brd

C875  Q_CAP_DIFFBUS  DIFF BUS_0.22UF 6.3V 20% X6S  pkg C0201  page 64 : \1\ = P5E_CPU0_P3_TX_C_DP<13> ; \2\ = P5E_CPU0_P3_TX_DP<13>
R160  Q_RES  33 5% CHIP  pkg 0402LF  page 80 : A = JTAG_SCM_TRST_R_N ; B = JTAG_SCM_TRST_N
R64  Q_RES  1K 1% EMPTY  pkg 0402LF  page 83 : A = SCM_SYS_PWRBTN_N ; B = P3V3_AUX

(kicad_pcb
	(version 20260206)
	(generator "pcbnew")
	(generator_version "10.0")
	(general
		(thickness 1.6)
		(legacy_teardrops no)
	)
	(paper "A4")
	(title_block
		(title "04192023_DAF0TMB3IC0_F0TG_MB_C_brd_V02_OCP.brd")
		(comment 1 "Grand Teton / footprints 4500-4502 of 8354")
	)
	(layers
		(0 "F.Cu" signal "TOP")
		(4 "In1.Cu" signal "GND")
		(6 "In2.Cu" signal "IN1")
		(8 "In3.Cu" signal "GND1")
		(10 "In4.Cu" signal "IN2")
		(12 "In5.Cu" signal "GND2")
		(14 "In6.Cu" signal "IN3")
		(16 "In7.Cu" signal "GND3")
		(18 "In8.Cu" signal "VCC")
		(20 "In9.Cu" signal "VCC1")
		(22 "In10.Cu" signal "GND4")
		(24 "In11.Cu" signal "IN4")
		(26 "In12.Cu" signal "GND5")
		(28 "In13.Cu" signal "IN5")
		(30 "In14.Cu" signal "GND6")
		(32 "In15.Cu" signal "IN6")
		(34 "In16.Cu" signal "GND7")
		(2 "B.Cu" signal "BOTTOM")
		(9 "F.Adhes" user "F.Adhesive")
		(11 "B.Adhes" user "B.Adhesive")
		(13 "F.Paste" user "Package Geometry/Pastemask Top")
		(15 "B.Paste" user "Package Geometry/Pastemask Bottom")
		(5 "F.SilkS" user "Ref Des/Silkscreen Top")
		(7 "B.SilkS" user "Ref Des/Silkscreen Bottom")
		(1 "F.Mask" user "Board Geometry/Soldermask Top")
		(3 "B.Mask" user "Board Geometry/Soldermask Bottom")
		(17 "Dwgs.User" user "User.Drawings")
		(19 "Cmts.User" user "User.Comments")
		(21 "Eco1.User" user "User.Eco1")
		(23 "Eco2.User" user "User.Eco2")
		(25 "Edge.Cuts" user "Board Geometry/Outline")
		(27 "Margin" user)
		(31 "F.CrtYd" user "Package Geometry/Place Bound Top")
		(29 "B.CrtYd" user "Package Geometry/Place Bound Bottom")
		(35 "F.Fab" user "Ref Des/Assembly Top")
		(33 "B.Fab" user "Ref Des/Assembly Bottom")
	)
	(footprint ""
		(layer "F.Cu")
		(at 391.616692 -378.95403 -90)
		(property "Reference" "C875"
			(at 0 0 270)
			(layer "F.SilkS")
			(hide yes)
			(effects
				(font
					(size 1.27 1.27)
				)
			)
		)
		(property "Value" ""
			(at 0 0 270)
			(layer "F.Fab")
			(effects
				(font
					(size 1.27 1.27)
				)
			)
		)
		(duplicate_pad_numbers_are_jumpers no)
		(fp_line
			(start -0.299974 0.150114)
			(end -0.299974 -0.150114)
			(stroke
				(width 0.1)
				(type default)
			)
			(layer "F.Fab")
		)
		(fp_line
			(start 0.299974 0.150114)
			(end -0.299974 0.150114)
			(stroke
				(width 0.1)
				(type default)
			)
			(layer "F.Fab")
		)
		(fp_line
			(start -0.299974 -0.150114)
			(end 0.299974 -0.150114)
			(stroke
				(width 0.1)
				(type default)
			)
			(layer "F.Fab")
		)
		(fp_line
			(start 0.299974 -0.150114)
			(end 0.299974 0.150114)
			(stroke
				(width 0.1)
				(type default)
			)
			(layer "F.Fab")
		)
		(pad "1" smd rect
			(at -0.2667 0 270)
			(size 0.3048 0.381)
			(layers "F.Cu" "F.Mask" "F.Paste")
			(net "P5E_CPU0_P3_TX_C_DP<13>")
		)
		(pad "2" smd rect
			(at 0.2667 0 270)
			(size 0.3048 0.381)
			(layers "F.Cu" "F.Mask" "F.Paste")
			(net "P5E_CPU0_P3_TX_DP<13>")
		)
	)
	(footprint ""
		(layer "F.Cu")
		(at 167.132 -115.280948 180)
		(property "Reference" "R64"
			(at 0 0 180)
			(layer "F.SilkS")
			(hide yes)
			(effects
				(font
					(size 1.27 1.27)
				)
			)
		)
		(property "Value" ""
			(at 0 0 180)
			(layer "F.Fab")
			(effects
				(font
					(size 1.27 1.27)
				)
			)
		)
		(duplicate_pad_numbers_are_jumpers no)
		(fp_line
			(start 0.7874 0.4064)
			(end -0.7874 0.4064)
			(stroke
				(width 0.1524)
				(type default)
			)
			(layer "F.SilkS")
		)
		(fp_line
			(start 0.7874 -0.4064)
			(end 0.7874 0.4064)
			(stroke
				(width 0.1524)
				(type default)
			)
			(layer "F.SilkS")
		)
		(fp_line
			(start -0.7874 0.4064)
			(end -0.7874 -0.4064)
			(stroke
				(width 0.1524)
				(type default)
			)
			(layer "F.SilkS")
		)
		(fp_line
			(start -0.7874 -0.4064)
			(end 0.7874 -0.4064)
			(stroke
				(width 0.1524)
				(type default)
			)
			(layer "F.SilkS")
		)
		(fp_line
			(start 0.67945 0.3048)
			(end 0.120396 0.3048)
			(stroke
				(width 0.1)
				(type default)
			)
			(layer "F.Fab")
		)
		(fp_line
			(start 0.67945 -0.3048)
			(end 0.67945 0.3048)
			(stroke
				(width 0.1)
				(type default)
			)
			(layer "F.Fab")
		)
		(fp_line
			(start 0.12065 -0.2794)
			(end 0.12065 -0.3048)
			(stroke
				(width 0.1)
				(type default)
			)
			(layer "F.Fab")
		)
		(fp_line
			(start 0.12065 -0.3048)
			(end 0.67945 -0.3048)
			(stroke
				(width 0.1)
				(type default)
			)
			(layer "F.Fab")
		)
		(fp_line
			(start 0.120396 0.3048)
			(end 0.120396 0.2794)
			(stroke
				(width 0.1)
				(type default)
			)
			(layer "F.Fab")
		)
		(fp_line
			(start 0.120396 0.2794)
			(end -0.12065 0.2794)
			(stroke
				(width 0.1)
				(type default)
			)
			(layer "F.Fab")
		)
		(fp_line
			(start -0.12065 0.3048)
			(end -0.67945 0.3048)
			(stroke
				(width 0.1)
				(type default)
			)
			(layer "F.Fab")
		)
		(fp_line
			(start -0.12065 0.2794)
			(end -0.12065 0.3048)
			(stroke
				(width 0.1)
				(type default)
			)
			(layer "F.Fab")
		)
		(fp_line
			(start -0.12065 -0.2794)
			(end 0.12065 -0.2794)
			(stroke
				(width 0.1)
				(type default)
			)
			(layer "F.Fab")
		)
		(fp_line
			(start -0.12065 -0.305054)
			(end -0.12065 -0.2794)
			(stroke
				(width 0.1)
				(type default)
			)
			(layer "F.Fab")
		)
		(fp_line
			(start -0.67945 0.3048)
			(end -0.67945 -0.305054)
			(stroke
				(width 0.1)
				(type default)
			)
			(layer "F.Fab")
		)
		(fp_line
			(start -0.67945 -0.305054)
			(end -0.12065 -0.305054)
			(stroke
				(width 0.1)
				(type default)
			)
			(layer "F.Fab")
		)
		(pad "1" smd circle
			(at -0.40005 0 180)
			(size 0 0)
			(layers "F.Cu" "F.Mask" "F.Paste")
			(net "SCM_SYS_PWRBTN_N")
		)
		(pad "2" smd circle
			(at 0.40005 0 180)
			(size 0 0)
			(layers "F.Cu" "F.Mask" "F.Paste")
			(net "P3V3_AUX")
		)
	)
	(footprint ""
		(layer "F.Cu")
		(at 171.196 -114.264948 180)
		(property "Reference" "R160"
			(at 0 0 180)
			(layer "F.SilkS")
			(hide yes)
			(effects
				(font
					(size 1.27 1.27)
				)
			)
		)
		(property "Value" ""
			(at 0 0 180)
			(layer "F.Fab")
			(effects
				(font
					(size 1.27 1.27)
				)
			)
		)
		(duplicate_pad_numbers_are_jumpers no)
		(fp_line
			(start 0.7874 0.4064)
			(end -0.7874 0.4064)
			(stroke
				(width 0.1524)
				(type default)
			)
			(layer "F.SilkS")
		)
		(fp_line
			(start 0.7874 -0.4064)
			(end 0.7874 0.4064)
			(stroke
				(width 0.1524)
				(type default)
			)
			(layer "F.SilkS")
		)
		(fp_line
			(start -0.7874 0.4064)
			(end -0.7874 -0.4064)
			(stroke
				(width 0.1524)
				(type default)
			)
			(layer "F.SilkS")
		)
		(fp_line
			(start -0.7874 -0.4064)
			(end 0.7874 -0.4064)
			(stroke
				(width 0.1524)
				(type default)
			)
			(layer "F.SilkS")
		)
		(fp_line
			(start 0.67945 0.3048)
			(end 0.120396 0.3048)
			(stroke
				(width 0.1)
				(type default)
			)
			(layer "F.Fab")
		)
		(fp_line
			(start 0.67945 -0.3048)
			(end 0.67945 0.3048)
			(stroke
				(width 0.1)
				(type default)
			)
			(layer "F.Fab")
		)
		(fp_line
			(start 0.12065 -0.2794)
			(end 0.12065 -0.3048)
			(stroke
				(width 0.1)
				(type default)
			)
			(layer "F.Fab")
		)
		(fp_line
			(start 0.12065 -0.3048)
			(end 0.67945 -0.3048)
			(stroke
				(width 0.1)
				(type default)
			)
			(layer "F.Fab")
		)
		(fp_line
			(start 0.120396 0.3048)
			(end 0.120396 0.2794)
			(stroke
				(width 0.1)
				(type default)
			)
			(layer "F.Fab")
		)
		(fp_line
			(start 0.120396 0.2794)
			(end -0.12065 0.2794)
			(stroke
				(width 0.1)
				(type default)
			)
			(layer "F.Fab")
		)
		(fp_line
			(start -0.12065 0.3048)
			(end -0.67945 0.3048)
			(stroke
				(width 0.1)
				(type default)
			)
			(layer "F.Fab")
		)
		(fp_line
			(start -0.12065 0.2794)
			(end -0.12065 0.3048)
			(stroke
				(width 0.1)
				(type default)
			)
			(layer "F.Fab")
		)
		(fp_line
			(start -0.12065 -0.2794)
			(end 0.12065 -0.2794)
			(stroke
				(width 0.1)
				(type default)
			)
			(layer "F.Fab")
		)
		(fp_line
			(start -0.12065 -0.305054)
			(end -0.12065 -0.2794)
			(stroke
				(width 0.1)
				(type default)
			)
			(layer "F.Fab")
		)
		(fp_line
			(start -0.67945 0.3048)
			(end -0.67945 -0.305054)
			(stroke
				(width 0.1)
				(type default)
			)
			(layer "F.Fab")
		)
		(fp_line
			(start -0.67945 -0.305054)
			(end -0.12065 -0.305054)
			(stroke
				(width 0.1)
				(type default)
			)
			(layer "F.Fab")
		)
		(pad "1" smd circle
			(at -0.40005 0 180)
			(size 0 0)
			(layers "F.Cu" "F.Mask" "F.Paste")
			(net "JTAG_SCM_TRST_R_N")
		)
		(pad "2" smd circle
			(at 0.40005 0 180)
			(size 0 0)
			(layers "F.Cu" "F.Mask" "F.Paste")
			(net "JTAG_SCM_TRST_N")
		)
	)
)
